(kicad_pcb
	(version 20260206)
	(generator "pcbnew")
	(generator_version "10.0")
	(general
		(thickness 1.6)
		(legacy_teardrops no)
	)
	(paper "A4")
	(title_block
		(title "fcb — Lightning_FCB_BRD.brd")
		(comment 1 "Lightning (Wiwynn / Facebook NVMe JBOF) / footprints 73-79 of 495")
	)
	(layers
		(0 "F.Cu" signal "TOP")
		(4 "In1.Cu" signal "L2GND")
		(6 "In2.Cu" signal "L3VCC")
		(2 "B.Cu" signal "BOTTOM")
		(9 "F.Adhes" user "F.Adhesive")
		(11 "B.Adhes" user "B.Adhesive")
		(13 "F.Paste" user "Package Geometry/Pastemask Top")
		(15 "B.Paste" user "Package Geometry/Pastemask Bottom")
		(5 "F.SilkS" user "Ref Des/Silkscreen Top")
		(7 "B.SilkS" user "Ref Des/Silkscreen Bottom")
		(1 "F.Mask" user "Board Geometry/Soldermask Top")
		(3 "B.Mask" user "Board Geometry/Soldermask Bottom")
		(17 "Dwgs.User" user "User.Drawings")
		(19 "Cmts.User" user "User.Comments")
		(21 "Eco1.User" user "User.Eco1")
		(23 "Eco2.User" user "User.Eco2")
		(25 "Edge.Cuts" user "Board Geometry/Outline")
		(27 "Margin" user)
		(31 "F.CrtYd" user "Package Geometry/Place Bound Top")
		(29 "B.CrtYd" user "Package Geometry/Place Bound Bottom")
		(35 "F.Fab" user "Ref Des/Assembly Top")
		(33 "B.Fab" user "Ref Des/Assembly Bottom")
	)
	(footprint ""
		(layer "F.Cu")
		(at 39.064184 -359.41 90)
		(property "Reference" "PR58"
			(at 0 0 90)
			(layer "F.SilkS")
			(hide yes)
			(effects
				(font
					(size 1.27 1.27)
				)
			)
		)
		(property "Value" "10KR2F-2-GP"
			(at 0.064008 -3.993896 90)
			(unlocked yes)
			(layer "F.Fab")
			(hide yes)
			(effects
				(font
					(size 1.016 1.016)
					(thickness 0.1524)
				)
			)
		)
		(property "Device Type" "R402H16"
			(at 0.064008 -5.517896 90)
			(unlocked yes)
			(layer "F.Fab")
			(hide yes)
			(effects
				(font
					(size 1.016 1.016)
					(thickness 0.1524)
				)
			)
		)
		(duplicate_pad_numbers_are_jumpers no)
		(fp_line
			(start 0.508 -0.9398)
			(end -0.508 -0.9398)
			(stroke
				(width 0.1524)
				(type default)
			)
			(layer "F.SilkS")
		)
		(fp_line
			(start -0.508 -0.9398)
			(end -0.508 0.9398)
			(stroke
				(width 0.1524)
				(type default)
			)
			(layer "F.SilkS")
		)
		(fp_rect
			(start -0.508 0.9398)
			(end 0.508 -0.9398)
			(stroke
				(width 0)
				(type default)
			)
			(fill no)
			(layer "F.CrtYd")
		)
		(fp_rect
			(start -0.508 0.9398)
			(end 0.508 -0.9398)
			(stroke
				(width 0)
				(type default)
			)
			(fill no)
			(layer "F.Fab")
		)
		(pad "1" smd custom
			(at 0 -0.4445 90)
			(size 0.1397 0.1397)
			(layers "F.Cu" "F.Mask" "F.Paste")
			(net "P12V_AUX")
			(options
				(clearance outline)
				(anchor circle)
			)
			(primitives
				(gr_poly
					(pts
						(arc
							(start -0.1778 -0.2794)
							(mid -0.249642 -0.249642)
							(end -0.2794 -0.1778)
						)
						(arc
							(start -0.2794 0.1778)
							(mid -0.249642 0.249642)
							(end -0.1778 0.2794)
						)
						(arc
							(start 0.1778 0.2794)
							(mid 0.249642 0.249642)
							(end 0.2794 0.1778)
						)
						(arc
							(start 0.2794 -0.1778)
							(mid 0.249642 -0.249642)
							(end 0.1778 -0.2794)
						)
					)
					(width 0)
					(fill yes)
				)
			)
		)
		(pad "2" smd custom
			(at 0 0.4445 90)
			(size 0.1397 0.1397)
			(layers "F.Cu" "F.Mask" "F.Paste")
			(net "OTP_RETRY_C")
			(options
				(clearance outline)
				(anchor circle)
			)
			(primitives
				(gr_poly
					(pts
						(arc
							(start -0.1778 -0.2794)
							(mid -0.249642 -0.249642)
							(end -0.2794 -0.1778)
						)
						(arc
							(start -0.2794 0.1778)
							(mid -0.249642 0.249642)
							(end -0.1778 0.2794)
						)
						(arc
							(start 0.1778 0.2794)
							(mid 0.249642 0.249642)
							(end 0.2794 0.1778)
						)
						(arc
							(start 0.2794 -0.1778)
							(mid 0.249642 -0.249642)
							(end 0.1778 -0.2794)
						)
					)
					(width 0)
					(fill yes)
				)
			)
		)
	)
	(footprint ""
		(layer "F.Cu")
		(at 37.465 -366.014 180)
		(property "Reference" "PQ4"
			(at 0 0 180)
			(layer "F.SilkS")
			(hide yes)
			(effects
				(font
					(size 1.27 1.27)
				)
			)
		)
		(property "Value" "MMBT3906-3-GP"
			(at 0.10287 -10.29843 180)
			(unlocked yes)
			(layer "F.Fab")
			(hide yes)
			(effects
				(font
					(size 1.016 1.016)
					(thickness 0.1524)
				)
			)
		)
		(property "Device Type" "SOT23CBE2D4H44"
			(at 0.10287 -12.20343 180)
			(unlocked yes)
			(layer "F.Fab")
			(hide yes)
			(effects
				(font
					(size 1.016 1.016)
					(thickness 0.1524)
				)
			)
		)
		(duplicate_pad_numbers_are_jumpers no)
		(fp_line
			(start 1.651 1.778)
			(end 1.651 -1.778)
			(stroke
				(width 0.1524)
				(type default)
			)
			(layer "F.SilkS")
		)
		(fp_line
			(start 1.651 -1.778)
			(end -1.651 -1.778)
			(stroke
				(width 0.1524)
				(type default)
			)
			(layer "F.SilkS")
		)
		(fp_line
			(start -1.651 1.778)
			(end 1.651 1.778)
			(stroke
				(width 0.1524)
				(type default)
			)
			(layer "F.SilkS")
		)
		(fp_line
			(start -1.651 -1.778)
			(end -1.651 1.778)
			(stroke
				(width 0.1524)
				(type default)
			)
			(layer "F.SilkS")
		)
		(fp_poly
			(pts
				(xy -1.778 1.8796) (xy -1.778 -1.8796) (xy 1.778 -1.8796) (xy 1.778 1.8796)
			)
			(stroke
				(width 0)
				(type default)
			)
			(fill no)
			(layer "F.CrtYd")
		)
		(fp_poly
			(pts
				(xy -1.778 1.8796) (xy -1.778 -1.8796) (xy 1.778 -1.8796) (xy 1.778 1.8796)
			)
			(stroke
				(width 0)
				(type default)
			)
			(fill no)
			(layer "F.Fab")
		)
		(pad "B" smd custom
			(at -0.98425 0.9525 180)
			(size 0.1905 0.1905)
			(layers "F.Cu" "F.Mask" "F.Paste")
			(net "ADM1276_LATCH_B")
			(options
				(clearance outline)
				(anchor circle)
			)
			(primitives
				(gr_poly
					(pts
						(arc
							(start -0.1778 0.5715)
							(mid -0.321484 0.511984)
							(end -0.381 0.3683)
						)
						(arc
							(start -0.381 -0.3683)
							(mid -0.321484 -0.511984)
							(end -0.1778 -0.5715)
						)
						(arc
							(start 0.1778 -0.5715)
							(mid 0.321484 -0.511984)
							(end 0.381 -0.3683)
						)
						(arc
							(start 0.381 0.3683)
							(mid 0.321484 0.511984)
							(end 0.1778 0.5715)
						)
					)
					(width 0)
					(fill yes)
				)
			)
		)
		(pad "C" smd custom
			(at 0 -0.9525 180)
			(size 0.1905 0.1905)
			(layers "F.Cu" "F.Mask" "F.Paste")
			(net "TEMP_ALM#_REVERSE_R")
			(options
				(clearance outline)
				(anchor circle)
			)
			(primitives
				(gr_poly
					(pts
						(arc
							(start -0.1778 0.5715)
							(mid -0.321484 0.511984)
							(end -0.381 0.3683)
						)
						(arc
							(start -0.381 -0.3683)
							(mid -0.321484 -0.511984)
							(end -0.1778 -0.5715)
						)
						(arc
							(start 0.1778 -0.5715)
							(mid 0.321484 -0.511984)
							(end 0.381 -0.3683)
						)
						(arc
							(start 0.381 0.3683)
							(mid 0.321484 0.511984)
							(end 0.1778 0.5715)
						)
					)
					(width 0)
					(fill yes)
				)
			)
		)
		(pad "E" smd custom
			(at 0.98425 0.9525 180)
			(size 0.1905 0.1905)
			(layers "F.Cu" "F.Mask" "F.Paste")
			(net "ADM1276_EN_NET")
			(options
				(clearance outline)
				(anchor circle)
			)
			(primitives
				(gr_poly
					(pts
						(arc
							(start -0.1778 0.5715)
							(mid -0.321484 0.511984)
							(end -0.381 0.3683)
						)
						(arc
							(start -0.381 -0.3683)
							(mid -0.321484 -0.511984)
							(end -0.1778 -0.5715)
						)
						(arc
							(start 0.1778 -0.5715)
							(mid 0.321484 -0.511984)
							(end 0.381 -0.3683)
						)
						(arc
							(start 0.381 0.3683)
							(mid 0.321484 0.511984)
							(end 0.1778 0.5715)
						)
					)
					(width 0)
					(fill yes)
				)
			)
		)
	)
	(footprint ""
		(layer "F.Cu")
		(at 45.466 -179.451)
		(property "Reference" "TP21"
			(at 0 0 0)
			(layer "F.SilkS")
			(hide yes)
			(effects
				(font
					(size 1.27 1.27)
				)
			)
		)
		(property "Value" "TPAD32-GP"
			(at 0 -3.166364 0)
			(unlocked yes)
			(layer "F.Fab")
			(hide yes)
			(effects
				(font
					(size 1.016 1.016)
					(thickness 0.1524)
				)
			)
		)
		(property "Device Type" "TPAD32"
			(at 0 -4.690618 0)
			(unlocked yes)
			(layer "F.Fab")
			(hide yes)
			(effects
				(font
					(size 1.016 1.016)
					(thickness 0.1524)
				)
			)
		)
		(duplicate_pad_numbers_are_jumpers no)
		(fp_poly
			(pts
				(arc
					(start 0.7112 0)
					(mid -0.7112 0)
					(end 0.7112 0)
				)
			)
			(stroke
				(width 0)
				(type default)
			)
			(fill no)
			(layer "F.CrtYd")
		)
		(fp_poly
			(pts
				(arc
					(start 0.7112 0)
					(mid -0.7112 0)
					(end 0.7112 0)
				)
			)
			(stroke
				(width 0)
				(type default)
			)
			(fill no)
			(layer "F.Fab")
		)
		(pad "1" smd circle
			(at 0 0)
			(size 0.8128 0.8128)
			(layers "F.Cu" "F.Mask" "F.Paste")
			(net "D_LATCH_Q#")
		)
	)
	(footprint ""
		(layer "F.Cu")
		(at 28.067 -238.252 180)
		(property "Reference" "R39"
			(at 0 0 180)
			(layer "F.SilkS")
			(hide yes)
			(effects
				(font
					(size 1.27 1.27)
				)
			)
		)
		(property "Value" "4K7R2J-2-GP"
			(at 0.064008 -3.993896 180)
			(unlocked yes)
			(layer "F.Fab")
			(hide yes)
			(effects
				(font
					(size 1.016 1.016)
					(thickness 0.1524)
				)
			)
		)
		(property "Device Type" "R402H16"
			(at 0.064008 -5.517896 180)
			(unlocked yes)
			(layer "F.Fab")
			(hide yes)
			(effects
				(font
					(size 1.016 1.016)
					(thickness 0.1524)
				)
			)
		)
		(duplicate_pad_numbers_are_jumpers no)
		(fp_line
			(start 0.508 -0.9398)
			(end -0.508 -0.9398)
			(stroke
				(width 0.1524)
				(type default)
			)
			(layer "F.SilkS")
		)
		(fp_line
			(start -0.508 -0.9398)
			(end -0.508 0.9398)
			(stroke
				(width 0.1524)
				(type default)
			)
			(layer "F.SilkS")
		)
		(fp_rect
			(start -0.508 0.9398)
			(end 0.508 -0.9398)
			(stroke
				(width 0)
				(type default)
			)
			(fill no)
			(layer "F.CrtYd")
		)
		(fp_rect
			(start -0.508 0.9398)
			(end 0.508 -0.9398)
			(stroke
				(width 0)
				(type default)
			)
			(fill no)
			(layer "F.Fab")
		)
		(pad "1" smd custom
			(at 0 -0.4445 180)
			(size 0.1397 0.1397)
			(layers "F.Cu" "F.Mask" "F.Paste")
			(net "P3V3")
			(options
				(clearance outline)
				(anchor circle)
			)
			(primitives
				(gr_poly
					(pts
						(arc
							(start -0.1778 -0.2794)
							(mid -0.249642 -0.249642)
							(end -0.2794 -0.1778)
						)
						(arc
							(start -0.2794 0.1778)
							(mid -0.249642 0.249642)
							(end -0.1778 0.2794)
						)
						(arc
							(start 0.1778 0.2794)
							(mid 0.249642 0.249642)
							(end 0.2794 0.1778)
						)
						(arc
							(start 0.2794 -0.1778)
							(mid 0.249642 -0.249642)
							(end 0.1778 -0.2794)
						)
					)
					(width 0)
					(fill yes)
				)
			)
		)
		(pad "2" smd custom
			(at 0 0.4445 180)
			(size 0.1397 0.1397)
			(layers "F.Cu" "F.Mask" "F.Paste")
			(net "FCB_EEPROM_A0")
			(options
				(clearance outline)
				(anchor circle)
			)
			(primitives
				(gr_poly
					(pts
						(arc
							(start -0.1778 -0.2794)
							(mid -0.249642 -0.249642)
							(end -0.2794 -0.1778)
						)
						(arc
							(start -0.2794 0.1778)
							(mid -0.249642 0.249642)
							(end -0.1778 0.2794)
						)
						(arc
							(start 0.1778 0.2794)
							(mid 0.249642 0.249642)
							(end 0.2794 0.1778)
						)
						(arc
							(start 0.2794 -0.1778)
							(mid 0.249642 -0.249642)
							(end 0.1778 -0.2794)
						)
					)
					(width 0)
					(fill yes)
				)
			)
		)
	)
	(footprint ""
		(layer "F.Cu")
		(at 15.3924 -49.0982 180)
		(property "Reference" "R184"
			(at 0 0 180)
			(layer "F.SilkS")
			(hide yes)
			(effects
				(font
					(size 1.27 1.27)
				)
			)
		)
		(property "Value" "0R2J-2-GP"
			(at 0.064008 -3.993896 180)
			(unlocked yes)
			(layer "F.Fab")
			(hide yes)
			(effects
				(font
					(size 1.016 1.016)
					(thickness 0.1524)
				)
			)
		)
		(property "Device Type" "R402H16"
			(at 0.064008 -5.517896 180)
			(unlocked yes)
			(layer "F.Fab")
			(hide yes)
			(effects
				(font
					(size 1.016 1.016)
					(thickness 0.1524)
				)
			)
		)
		(duplicate_pad_numbers_are_jumpers no)
		(fp_line
			(start 0.508 -0.9398)
			(end -0.508 -0.9398)
			(stroke
				(width 0.1524)
				(type default)
			)
			(layer "F.SilkS")
		)
		(fp_line
			(start -0.508 -0.9398)
			(end -0.508 0.9398)
			(stroke
				(width 0.1524)
				(type default)
			)
			(layer "F.SilkS")
		)
		(fp_rect
			(start -0.508 0.9398)
			(end 0.508 -0.9398)
			(stroke
				(width 0)
				(type default)
			)
			(fill no)
			(layer "F.CrtYd")
		)
		(fp_rect
			(start -0.508 0.9398)
			(end 0.508 -0.9398)
			(stroke
				(width 0)
				(type default)
			)
			(fill no)
			(layer "F.Fab")
		)
		(pad "1" smd custom
			(at 0 -0.4445 180)
			(size 0.1397 0.1397)
			(layers "F.Cu" "F.Mask" "F.Paste")
			(net "SD_LATCH_RELEASE_L")
			(options
				(clearance outline)
				(anchor circle)
			)
			(primitives
				(gr_poly
					(pts
						(arc
							(start -0.1778 -0.2794)
							(mid -0.249642 -0.249642)
							(end -0.2794 -0.1778)
						)
						(arc
							(start -0.2794 0.1778)
							(mid -0.249642 0.249642)
							(end -0.1778 0.2794)
						)
						(arc
							(start 0.1778 0.2794)
							(mid 0.249642 0.249642)
							(end 0.2794 0.1778)
						)
						(arc
							(start 0.2794 -0.1778)
							(mid 0.249642 -0.249642)
							(end 0.1778 -0.2794)
						)
					)
					(width 0)
					(fill yes)
				)
			)
		)
		(pad "2" smd custom
			(at 0 0.4445 180)
			(size 0.1397 0.1397)
			(layers "F.Cu" "F.Mask" "F.Paste")
			(net "TEMP_ALM#_REVERSE_R")
			(options
				(clearance outline)
				(anchor circle)
			)
			(primitives
				(gr_poly
					(pts
						(arc
							(start -0.1778 -0.2794)
							(mid -0.249642 -0.249642)
							(end -0.2794 -0.1778)
						)
						(arc
							(start -0.2794 0.1778)
							(mid -0.249642 0.249642)
							(end -0.1778 0.2794)
						)
						(arc
							(start 0.1778 0.2794)
							(mid 0.249642 0.249642)
							(end 0.2794 0.1778)
						)
						(arc
							(start 0.2794 -0.1778)
							(mid 0.249642 -0.249642)
							(end 0.1778 -0.2794)
						)
					)
					(width 0)
					(fill yes)
				)
			)
		)
	)
	(footprint ""
		(layer "F.Cu")
		(at 8.733028 -67.111118 -90)
		(property "Reference" "R111"
			(at 0 0 270)
			(layer "F.SilkS")
			(hide yes)
			(effects
				(font
					(size 1.27 1.27)
				)
			)
		)
		(property "Value" "2KR2F-3-GP"
			(at 0.064008 -3.993896 270)
			(unlocked yes)
			(layer "F.Fab")
			(hide yes)
			(effects
				(font
					(size 1.016 1.016)
					(thickness 0.1524)
				)
			)
		)
		(property "Device Type" "R402H16"
			(at 0.064008 -5.517896 270)
			(unlocked yes)
			(layer "F.Fab")
			(hide yes)
			(effects
				(font
					(size 1.016 1.016)
					(thickness 0.1524)
				)
			)
		)
		(duplicate_pad_numbers_are_jumpers no)
		(fp_line
			(start -0.508 -0.9398)
			(end -0.508 0.9398)
			(stroke
				(width 0.1524)
				(type default)
			)
			(layer "F.SilkS")
		)
		(fp_line
			(start 0.508 -0.9398)
			(end -0.508 -0.9398)
			(stroke
				(width 0.1524)
				(type default)
			)
			(layer "F.SilkS")
		)
		(fp_rect
			(start -0.508 0.9398)
			(end 0.508 -0.9398)
			(stroke
				(width 0)
				(type default)
			)
			(fill no)
			(layer "F.CrtYd")
		)
		(fp_rect
			(start -0.508 0.9398)
			(end 0.508 -0.9398)
			(stroke
				(width 0)
				(type default)
			)
			(fill no)
			(layer "F.Fab")
		)
		(pad "1" smd custom
			(at 0 -0.4445 270)
			(size 0.1397 0.1397)
			(layers "F.Cu" "F.Mask" "F.Paste")
			(net "LED_DR_LED5")
			(options
				(clearance outline)
				(anchor circle)
			)
			(primitives
				(gr_poly
					(pts
						(arc
							(start -0.1778 -0.2794)
							(mid -0.249642 -0.249642)
							(end -0.2794 -0.1778)
						)
						(arc
							(start -0.2794 0.1778)
							(mid -0.249642 0.249642)
							(end -0.1778 0.2794)
						)
						(arc
							(start 0.1778 0.2794)
							(mid 0.249642 0.249642)
							(end 0.2794 0.1778)
						)
						(arc
							(start 0.2794 -0.1778)
							(mid 0.249642 -0.249642)
							(end 0.1778 -0.2794)
						)
					)
					(width 0)
					(fill yes)
				)
			)
		)
		(pad "2" smd custom
			(at 0 0.4445 270)
			(size 0.1397 0.1397)
			(layers "F.Cu" "F.Mask" "F.Paste")
			(net "LED_DR_LED5_B")
			(options
				(clearance outline)
				(anchor circle)
			)
			(primitives
				(gr_poly
					(pts
						(arc
							(start -0.1778 -0.2794)
							(mid -0.249642 -0.249642)
							(end -0.2794 -0.1778)
						)
						(arc
							(start -0.2794 0.1778)
							(mid -0.249642 0.249642)
							(end -0.1778 0.2794)
						)
						(arc
							(start 0.1778 0.2794)
							(mid 0.249642 0.249642)
							(end 0.2794 0.1778)
						)
						(arc
							(start 0.2794 -0.1778)
							(mid 0.249642 -0.249642)
							(end 0.1778 -0.2794)
						)
					)
					(width 0)
					(fill yes)
				)
			)
		)
	)
	(footprint ""
		(layer "F.Cu")
		(at 20.701 -185.5216)
		(property "Reference" "R85"
			(at 0 0 0)
			(layer "F.SilkS")
			(hide yes)
			(effects
				(font
					(size 1.27 1.27)
				)
			)
		)
		(property "Value" "27KR3F-GP"
			(at -0.0254 -2.5146 0)
			(unlocked yes)
			(layer "F.Fab")
			(hide yes)
			(effects
				(font
					(size 1.016 1.016)
					(thickness 0.1524)
				)
			)
		)
		(property "Device Type" "R603H22"
			(at -0.0254 -4.0386 0)
			(unlocked yes)
			(layer "F.Fab")
			(hide yes)
			(effects
				(font
					(size 1.016 1.016)
					(thickness 0.1524)
				)
			)
		)
		(duplicate_pad_numbers_are_jumpers no)
		(fp_line
			(start -0.4826 0)
			(end -0.2032 0)
			(stroke
				(width 0.2032)
				(type default)
			)
			(layer "F.SilkS")
		)
		(fp_line
			(start 0.2032 0)
			(end 0.4826 0)
			(stroke
				(width 0.2032)
				(type default)
			)
			(layer "F.SilkS")
		)
		(fp_rect
			(start -0.5842 1.3335)
			(end 0.5842 -1.3335)
			(stroke
				(width 0)
				(type default)
			)
			(fill no)
			(layer "F.CrtYd")
		)
		(fp_rect
			(start -0.5842 1.3335)
			(end 0.5842 -1.3335)
			(stroke
				(width 0)
				(type default)
			)
			(fill no)
			(layer "F.Fab")
		)
		(pad "1" smd custom
			(at 0 -0.762)
			(size 0.2159 0.2159)
			(layers "F.Cu" "F.Mask" "F.Paste")
			(net "FAN_TACH8")
			(options
				(clearance outline)
				(anchor circle)
			)
			(primitives
				(gr_poly
					(pts
						(arc
							(start -0.3302 -0.4318)
							(mid -0.402042 -0.402042)
							(end -0.4318 -0.3302)
						)
						(arc
							(start -0.4318 0.3302)
							(mid -0.402042 0.402042)
							(end -0.3302 0.4318)
						)
						(arc
							(start 0.3302 0.4318)
							(mid 0.402042 0.402042)
							(end 0.4318 0.3302)
						)
						(arc
							(start 0.4318 -0.3302)
							(mid 0.402042 -0.402042)
							(end 0.3302 -0.4318)
						)
					)
					(width 0)
					(fill yes)
				)
			)
		)
		(pad "2" smd custom
			(at 0 0.762)
			(size 0.2159 0.2159)
			(layers "F.Cu" "F.Mask" "F.Paste")
			(net "FANIN_8")
			(options
				(clearance outline)
				(anchor circle)
			)
			(primitives
				(gr_poly
					(pts
						(arc
							(start -0.3302 -0.4318)
							(mid -0.402042 -0.402042)
							(end -0.4318 -0.3302)
						)
						(arc
							(start -0.4318 0.3302)
							(mid -0.402042 0.402042)
							(end -0.3302 0.4318)
						)
						(arc
							(start 0.3302 0.4318)
							(mid 0.402042 0.402042)
							(end 0.4318 0.3302)
						)
						(arc
							(start 0.4318 -0.3302)
							(mid 0.402042 -0.402042)
							(end 0.3302 -0.4318)
						)
					)
					(width 0)
					(fill yes)
				)
			)
		)
	)
)
